(kicad_pcb
	(version 20260206)
	(generator "pcbnew")
	(generator_version "10.0")
	(general
		(thickness 1.6)
		(legacy_teardrops no)
	)
	(paper "A4")
	(title_block
		(title "01162023_DA0F0TEBIF0_F0T_Expander_BD_F_brd_V02_OCP.brd")
		(comment 1 "Grand Teton / footprints 4664-4670 of 9728")
	)
	(layers
		(0 "F.Cu" signal "TOP")
		(4 "In1.Cu" signal "GND")
		(6 "In2.Cu" signal "VCC")
		(8 "In3.Cu" signal "VCC1")
		(10 "In4.Cu" signal "GND1")
		(12 "In5.Cu" signal "IN1")
		(14 "In6.Cu" signal "GND2")
		(16 "In7.Cu" signal "IN2")
		(18 "In8.Cu" signal "GND3")
		(20 "In9.Cu" signal "IN3")
		(22 "In10.Cu" signal "GND4")
		(24 "In11.Cu" signal "IN4")
		(26 "In12.Cu" signal "GND5")
		(28 "In13.Cu" signal "IN5")
		(30 "In14.Cu" signal "GND6")
		(32 "In15.Cu" signal "IN6")
		(34 "In16.Cu" signal "GND7")
		(2 "B.Cu" signal "BOTTOM")
		(9 "F.Adhes" user "F.Adhesive")
		(11 "B.Adhes" user "B.Adhesive")
		(13 "F.Paste" user "Package Geometry/Pastemask Top")
		(15 "B.Paste" user "Package Geometry/Pastemask Bottom")
		(5 "F.SilkS" user "Ref Des/Silkscreen Top")
		(7 "B.SilkS" user "Ref Des/Silkscreen Bottom")
		(1 "F.Mask" user "Board Geometry/Soldermask Top")
		(3 "B.Mask" user "Board Geometry/Soldermask Bottom")
		(17 "Dwgs.User" user "User.Drawings")
		(19 "Cmts.User" user "User.Comments")
		(21 "Eco1.User" user "User.Eco1")
		(23 "Eco2.User" user "User.Eco2")
		(25 "Edge.Cuts" user "Board Geometry/Outline")
		(27 "Margin" user)
		(31 "F.CrtYd" user "Package Geometry/Place Bound Top")
		(29 "B.CrtYd" user "Package Geometry/Place Bound Bottom")
		(35 "F.Fab" user "Ref Des/Assembly Top")
		(33 "B.Fab" user "Ref Des/Assembly Bottom")
	)
	(footprint ""
		(layer "F.Cu")
		(at 56.715152 -59.546236 90)
		(property "Reference" "C2889"
			(at 0 0 90)
			(layer "F.SilkS")
			(hide yes)
			(effects
				(font
					(size 1.27 1.27)
				)
			)
		)
		(property "Value" ""
			(at 0 0 90)
			(layer "F.Fab")
			(effects
				(font
					(size 1.27 1.27)
				)
			)
		)
		(duplicate_pad_numbers_are_jumpers no)
		(fp_line
			(start 0.7874 -0.4064)
			(end 0.7874 0.4064)
			(stroke
				(width 0.1524)
				(type default)
			)
			(layer "F.SilkS")
		)
		(fp_line
			(start -0.7874 -0.4064)
			(end 0.7874 -0.4064)
			(stroke
				(width 0.1524)
				(type default)
			)
			(layer "F.SilkS")
		)
		(fp_line
			(start 0.7874 0.4064)
			(end -0.7874 0.4064)
			(stroke
				(width 0.1524)
				(type default)
			)
			(layer "F.SilkS")
		)
		(fp_line
			(start -0.7874 0.4064)
			(end -0.7874 -0.4064)
			(stroke
				(width 0.1524)
				(type default)
			)
			(layer "F.SilkS")
		)
		(fp_line
			(start -0.12065 -0.305054)
			(end -0.12065 -0.2794)
			(stroke
				(width 0.1)
				(type default)
			)
			(layer "F.Fab")
		)
		(fp_line
			(start -0.67945 -0.305054)
			(end -0.12065 -0.305054)
			(stroke
				(width 0.1)
				(type default)
			)
			(layer "F.Fab")
		)
		(fp_line
			(start 0.67945 -0.3048)
			(end 0.67945 0.3048)
			(stroke
				(width 0.1)
				(type default)
			)
			(layer "F.Fab")
		)
		(fp_line
			(start 0.12065 -0.3048)
			(end 0.67945 -0.3048)
			(stroke
				(width 0.1)
				(type default)
			)
			(layer "F.Fab")
		)
		(fp_line
			(start 0.12065 -0.2794)
			(end 0.12065 -0.3048)
			(stroke
				(width 0.1)
				(type default)
			)
			(layer "F.Fab")
		)
		(fp_line
			(start -0.12065 -0.2794)
			(end 0.12065 -0.2794)
			(stroke
				(width 0.1)
				(type default)
			)
			(layer "F.Fab")
		)
		(fp_line
			(start 0.120396 0.2794)
			(end -0.12065 0.2794)
			(stroke
				(width 0.1)
				(type default)
			)
			(layer "F.Fab")
		)
		(fp_line
			(start -0.12065 0.2794)
			(end -0.12065 0.3048)
			(stroke
				(width 0.1)
				(type default)
			)
			(layer "F.Fab")
		)
		(fp_line
			(start 0.67945 0.3048)
			(end 0.120396 0.3048)
			(stroke
				(width 0.1)
				(type default)
			)
			(layer "F.Fab")
		)
		(fp_line
			(start 0.120396 0.3048)
			(end 0.120396 0.2794)
			(stroke
				(width 0.1)
				(type default)
			)
			(layer "F.Fab")
		)
		(fp_line
			(start -0.12065 0.3048)
			(end -0.67945 0.3048)
			(stroke
				(width 0.1)
				(type default)
			)
			(layer "F.Fab")
		)
		(fp_line
			(start -0.67945 0.3048)
			(end -0.67945 -0.305054)
			(stroke
				(width 0.1)
				(type default)
			)
			(layer "F.Fab")
		)
		(pad "1" smd circle
			(at -0.40005 0 90)
			(size 0 0)
			(layers "F.Cu" "F.Mask" "F.Paste")
			(net "SSD2_AUX_P3V3_EN_R")
		)
		(pad "2" smd circle
			(at 0.40005 0 90)
			(size 0 0)
			(layers "F.Cu" "F.Mask" "F.Paste")
			(net "GND")
		)
	)
	(footprint ""
		(layer "F.Cu")
		(at 239.721898 -84.351368 90)
		(property "Reference" "R6623"
			(at 0 0 90)
			(layer "F.SilkS")
			(hide yes)
			(effects
				(font
					(size 1.27 1.27)
				)
			)
		)
		(property "Value" ""
			(at 0 0 90)
			(layer "F.Fab")
			(effects
				(font
					(size 1.27 1.27)
				)
			)
		)
		(duplicate_pad_numbers_are_jumpers no)
		(fp_line
			(start 0.7874 -0.4064)
			(end 0.7874 0.4064)
			(stroke
				(width 0.1524)
				(type default)
			)
			(layer "F.SilkS")
		)
		(fp_line
			(start -0.7874 -0.4064)
			(end -0.00254 -0.4064)
			(stroke
				(width 0.1524)
				(type default)
			)
			(layer "F.SilkS")
		)
		(fp_line
			(start 0.7874 0.4064)
			(end -0.7874 0.4064)
			(stroke
				(width 0.1524)
				(type default)
			)
			(layer "F.SilkS")
		)
		(fp_line
			(start -0.12065 -0.305054)
			(end -0.12065 -0.2794)
			(stroke
				(width 0.1)
				(type default)
			)
			(layer "F.Fab")
		)
		(fp_line
			(start -0.67945 -0.305054)
			(end -0.12065 -0.305054)
			(stroke
				(width 0.1)
				(type default)
			)
			(layer "F.Fab")
		)
		(fp_line
			(start 0.67945 -0.3048)
			(end 0.67945 0.3048)
			(stroke
				(width 0.1)
				(type default)
			)
			(layer "F.Fab")
		)
		(fp_line
			(start 0.12065 -0.3048)
			(end 0.67945 -0.3048)
			(stroke
				(width 0.1)
				(type default)
			)
			(layer "F.Fab")
		)
		(fp_line
			(start 0.12065 -0.2794)
			(end 0.12065 -0.3048)
			(stroke
				(width 0.1)
				(type default)
			)
			(layer "F.Fab")
		)
		(fp_line
			(start -0.12065 -0.2794)
			(end 0.12065 -0.2794)
			(stroke
				(width 0.1)
				(type default)
			)
			(layer "F.Fab")
		)
		(fp_line
			(start 0.120396 0.2794)
			(end -0.12065 0.2794)
			(stroke
				(width 0.1)
				(type default)
			)
			(layer "F.Fab")
		)
		(fp_line
			(start -0.12065 0.2794)
			(end -0.12065 0.3048)
			(stroke
				(width 0.1)
				(type default)
			)
			(layer "F.Fab")
		)
		(fp_line
			(start 0.67945 0.3048)
			(end 0.120396 0.3048)
			(stroke
				(width 0.1)
				(type default)
			)
			(layer "F.Fab")
		)
		(fp_line
			(start 0.120396 0.3048)
			(end 0.120396 0.2794)
			(stroke
				(width 0.1)
				(type default)
			)
			(layer "F.Fab")
		)
		(fp_line
			(start -0.12065 0.3048)
			(end -0.67945 0.3048)
			(stroke
				(width 0.1)
				(type default)
			)
			(layer "F.Fab")
		)
		(fp_line
			(start -0.67945 0.3048)
			(end -0.67945 -0.305054)
			(stroke
				(width 0.1)
				(type default)
			)
			(layer "F.Fab")
		)
		(pad "1" smd rect
			(at -0.40005 0 270)
			(size 0.4572 0.508)
			(layers "F.Cu" "F.Mask" "F.Paste")
			(net "USB2_CP2108_CLI_DP")
		)
		(pad "2" smd rect
			(at 0.40005 0 270)
			(size 0.4572 0.508)
			(layers "F.Cu" "F.Mask" "F.Paste")
			(net "USB2_FT4232_CLI_R_DP")
		)
	)
	(footprint ""
		(layer "F.Cu")
		(at 235.623608 -151.975566 180)
		(property "Reference" "R1209"
			(at 0 0 180)
			(layer "F.SilkS")
			(hide yes)
			(effects
				(font
					(size 1.27 1.27)
				)
			)
		)
		(property "Value" ""
			(at 0 0 180)
			(layer "F.Fab")
			(effects
				(font
					(size 1.27 1.27)
				)
			)
		)
		(duplicate_pad_numbers_are_jumpers no)
		(fp_line
			(start 0.7874 0.4064)
			(end -0.7874 0.4064)
			(stroke
				(width 0.1524)
				(type default)
			)
			(layer "F.SilkS")
		)
		(fp_line
			(start 0.67945 0.3048)
			(end 0.120396 0.3048)
			(stroke
				(width 0.1)
				(type default)
			)
			(layer "F.Fab")
		)
		(fp_line
			(start 0.67945 -0.3048)
			(end 0.67945 0.3048)
			(stroke
				(width 0.1)
				(type default)
			)
			(layer "F.Fab")
		)
		(fp_line
			(start 0.12065 -0.2794)
			(end 0.12065 -0.3048)
			(stroke
				(width 0.1)
				(type default)
			)
			(layer "F.Fab")
		)
		(fp_line
			(start 0.12065 -0.3048)
			(end 0.67945 -0.3048)
			(stroke
				(width 0.1)
				(type default)
			)
			(layer "F.Fab")
		)
		(fp_line
			(start 0.120396 0.3048)
			(end 0.120396 0.2794)
			(stroke
				(width 0.1)
				(type default)
			)
			(layer "F.Fab")
		)
		(fp_line
			(start 0.120396 0.2794)
			(end -0.12065 0.2794)
			(stroke
				(width 0.1)
				(type default)
			)
			(layer "F.Fab")
		)
		(fp_line
			(start -0.12065 0.3048)
			(end -0.67945 0.3048)
			(stroke
				(width 0.1)
				(type default)
			)
			(layer "F.Fab")
		)
		(fp_line
			(start -0.12065 0.2794)
			(end -0.12065 0.3048)
			(stroke
				(width 0.1)
				(type default)
			)
			(layer "F.Fab")
		)
		(fp_line
			(start -0.12065 -0.2794)
			(end 0.12065 -0.2794)
			(stroke
				(width 0.1)
				(type default)
			)
			(layer "F.Fab")
		)
		(fp_line
			(start -0.12065 -0.305054)
			(end -0.12065 -0.2794)
			(stroke
				(width 0.1)
				(type default)
			)
			(layer "F.Fab")
		)
		(fp_line
			(start -0.67945 0.3048)
			(end -0.67945 -0.305054)
			(stroke
				(width 0.1)
				(type default)
			)
			(layer "F.Fab")
		)
		(fp_line
			(start -0.67945 -0.305054)
			(end -0.12065 -0.305054)
			(stroke
				(width 0.1)
				(type default)
			)
			(layer "F.Fab")
		)
		(pad "1" smd circle
			(at -0.40005 0 180)
			(size 0 0)
			(layers "F.Cu" "F.Mask" "F.Paste")
			(net "CLK_100M_PEX2_REF_R_DP")
		)
		(pad "2" smd circle
			(at 0.40005 0 180)
			(size 0 0)
			(layers "F.Cu" "F.Mask" "F.Paste")
			(net "CLK_100M_PEX2_REF_DP")
		)
	)
	(footprint ""
		(layer "F.Cu")
		(at 20.25523 -35.876738)
		(property "Reference" "R5869"
			(at 0 0 0)
			(layer "F.SilkS")
			(hide yes)
			(effects
				(font
					(size 1.27 1.27)
				)
			)
		)
		(property "Value" ""
			(at 0 0 0)
			(layer "F.Fab")
			(effects
				(font
					(size 1.27 1.27)
				)
			)
		)
		(duplicate_pad_numbers_are_jumpers no)
		(fp_line
			(start -0.7874 -0.4064)
			(end 0.7874 -0.4064)
			(stroke
				(width 0.1524)
				(type default)
			)
			(layer "F.SilkS")
		)
		(fp_line
			(start -0.7874 0.4064)
			(end -0.7874 -0.4064)
			(stroke
				(width 0.1524)
				(type default)
			)
			(layer "F.SilkS")
		)
		(fp_line
			(start 0.7874 -0.4064)
			(end 0.7874 0.4064)
			(stroke
				(width 0.1524)
				(type default)
			)
			(layer "F.SilkS")
		)
		(fp_line
			(start 0.7874 0.4064)
			(end -0.7874 0.4064)
			(stroke
				(width 0.1524)
				(type default)
			)
			(layer "F.SilkS")
		)
		(fp_line
			(start -0.67945 -0.305054)
			(end -0.12065 -0.305054)
			(stroke
				(width 0.1)
				(type default)
			)
			(layer "F.Fab")
		)
		(fp_line
			(start -0.67945 0.3048)
			(end -0.67945 -0.305054)
			(stroke
				(width 0.1)
				(type default)
			)
			(layer "F.Fab")
		)
		(fp_line
			(start -0.12065 -0.305054)
			(end -0.12065 -0.2794)
			(stroke
				(width 0.1)
				(type default)
			)
			(layer "F.Fab")
		)
		(fp_line
			(start -0.12065 -0.2794)
			(end 0.12065 -0.2794)
			(stroke
				(width 0.1)
				(type default)
			)
			(layer "F.Fab")
		)
		(fp_line
			(start -0.12065 0.2794)
			(end -0.12065 0.3048)
			(stroke
				(width 0.1)
				(type default)
			)
			(layer "F.Fab")
		)
		(fp_line
			(start -0.12065 0.3048)
			(end -0.67945 0.3048)
			(stroke
				(width 0.1)
				(type default)
			)
			(layer "F.Fab")
		)
		(fp_line
			(start 0.120396 0.2794)
			(end -0.12065 0.2794)
			(stroke
				(width 0.1)
				(type default)
			)
			(layer "F.Fab")
		)
		(fp_line
			(start 0.120396 0.3048)
			(end 0.120396 0.2794)
			(stroke
				(width 0.1)
				(type default)
			)
			(layer "F.Fab")
		)
		(fp_line
			(start 0.12065 -0.3048)
			(end 0.67945 -0.3048)
			(stroke
				(width 0.1)
				(type default)
			)
			(layer "F.Fab")
		)
		(fp_line
			(start 0.12065 -0.2794)
			(end 0.12065 -0.3048)
			(stroke
				(width 0.1)
				(type default)
			)
			(layer "F.Fab")
		)
		(fp_line
			(start 0.67945 -0.3048)
			(end 0.67945 0.3048)
			(stroke
				(width 0.1)
				(type default)
			)
			(layer "F.Fab")
		)
		(fp_line
			(start 0.67945 0.3048)
			(end 0.120396 0.3048)
			(stroke
				(width 0.1)
				(type default)
			)
			(layer "F.Fab")
		)
		(pad "1" smd circle
			(at -0.40005 0)
			(size 0 0)
			(layers "F.Cu" "F.Mask" "F.Paste")
			(net "P3V3_AUX")
		)
		(pad "2" smd circle
			(at 0.40005 0)
			(size 0 0)
			(layers "F.Cu" "F.Mask" "F.Paste")
			(net "PWRGD_P3V3_SSD1_D")
		)
	)
	(footprint ""
		(layer "F.Cu")
		(at 56.034686 -371.336062 180)
		(property "Reference" "C3987"
			(at 0 0 180)
			(layer "F.SilkS")
			(hide yes)
			(effects
				(font
					(size 1.27 1.27)
				)
			)
		)
		(property "Value" ""
			(at 0 0 180)
			(layer "F.Fab")
			(effects
				(font
					(size 1.27 1.27)
				)
			)
		)
		(duplicate_pad_numbers_are_jumpers no)
		(fp_line
			(start 0.299974 0.150114)
			(end -0.299974 0.150114)
			(stroke
				(width 0.1)
				(type default)
			)
			(layer "F.Fab")
		)
		(fp_line
			(start 0.299974 -0.150114)
			(end 0.299974 0.150114)
			(stroke
				(width 0.1)
				(type default)
			)
			(layer "F.Fab")
		)
		(fp_line
			(start -0.299974 0.150114)
			(end -0.299974 -0.150114)
			(stroke
				(width 0.1)
				(type default)
			)
			(layer "F.Fab")
		)
		(fp_line
			(start -0.299974 -0.150114)
			(end 0.299974 -0.150114)
			(stroke
				(width 0.1)
				(type default)
			)
			(layer "F.Fab")
		)
		(pad "1" smd rect
			(at -0.2667 0 180)
			(size 0.3048 0.381)
			(layers "F.Cu" "F.Mask" "F.Paste")
			(net "P4E_PEX0_STN3_TX_DN<48>")
		)
		(pad "2" smd rect
			(at 0.2667 0 180)
			(size 0.3048 0.381)
			(layers "F.Cu" "F.Mask" "F.Paste")
			(net "P4E_PEX0_STN3_TX_C_DN<48>")
		)
	)
	(footprint ""
		(layer "F.Cu")
		(at 435.291484 -96.811592 -90)
		(property "Reference" "R759"
			(at 0 0 270)
			(layer "F.SilkS")
			(hide yes)
			(effects
				(font
					(size 1.27 1.27)
				)
			)
		)
		(property "Value" ""
			(at 0 0 270)
			(layer "F.Fab")
			(effects
				(font
					(size 1.27 1.27)
				)
			)
		)
		(duplicate_pad_numbers_are_jumpers no)
		(fp_line
			(start -0.7874 0.4064)
			(end -0.7874 -0.4064)
			(stroke
				(width 0.1524)
				(type default)
			)
			(layer "F.SilkS")
		)
		(fp_line
			(start 0.7874 0.4064)
			(end -0.7874 0.4064)
			(stroke
				(width 0.1524)
				(type default)
			)
			(layer "F.SilkS")
		)
		(fp_line
			(start -0.7874 -0.4064)
			(end 0.7874 -0.4064)
			(stroke
				(width 0.1524)
				(type default)
			)
			(layer "F.SilkS")
		)
		(fp_line
			(start 0.7874 -0.4064)
			(end 0.7874 0.4064)
			(stroke
				(width 0.1524)
				(type default)
			)
			(layer "F.SilkS")
		)
		(fp_line
			(start -0.67945 0.3048)
			(end -0.67945 -0.305054)
			(stroke
				(width 0.1)
				(type default)
			)
			(layer "F.Fab")
		)
		(fp_line
			(start -0.12065 0.3048)
			(end -0.67945 0.3048)
			(stroke
				(width 0.1)
				(type default)
			)
			(layer "F.Fab")
		)
		(fp_line
			(start 0.120396 0.3048)
			(end 0.120396 0.2794)
			(stroke
				(width 0.1)
				(type default)
			)
			(layer "F.Fab")
		)
		(fp_line
			(start 0.67945 0.3048)
			(end 0.120396 0.3048)
			(stroke
				(width 0.1)
				(type default)
			)
			(layer "F.Fab")
		)
		(fp_line
			(start -0.12065 0.2794)
			(end -0.12065 0.3048)
			(stroke
				(width 0.1)
				(type default)
			)
			(layer "F.Fab")
		)
		(fp_line
			(start 0.120396 0.2794)
			(end -0.12065 0.2794)
			(stroke
				(width 0.1)
				(type default)
			)
			(layer "F.Fab")
		)
		(fp_line
			(start -0.12065 -0.2794)
			(end 0.12065 -0.2794)
			(stroke
				(width 0.1)
				(type default)
			)
			(layer "F.Fab")
		)
		(fp_line
			(start 0.12065 -0.2794)
			(end 0.12065 -0.3048)
			(stroke
				(width 0.1)
				(type default)
			)
			(layer "F.Fab")
		)
		(fp_line
			(start 0.12065 -0.3048)
			(end 0.67945 -0.3048)
			(stroke
				(width 0.1)
				(type default)
			)
			(layer "F.Fab")
		)
		(fp_line
			(start 0.67945 -0.3048)
			(end 0.67945 0.3048)
			(stroke
				(width 0.1)
				(type default)
			)
			(layer "F.Fab")
		)
		(fp_line
			(start -0.67945 -0.305054)
			(end -0.12065 -0.305054)
			(stroke
				(width 0.1)
				(type default)
			)
			(layer "F.Fab")
		)
		(fp_line
			(start -0.12065 -0.305054)
			(end -0.12065 -0.2794)
			(stroke
				(width 0.1)
				(type default)
			)
			(layer "F.Fab")
		)
		(pad "1" smd circle
			(at -0.40005 0 270)
			(size 0 0)
			(layers "F.Cu" "F.Mask" "F.Paste")
			(net "NIC7_ADC_A1")
		)
		(pad "2" smd circle
			(at 0.40005 0 270)
			(size 0 0)
			(layers "F.Cu" "F.Mask" "F.Paste")
			(net "P3V3_AUX")
		)
	)
	(footprint ""
		(layer "F.Cu")
		(at 6.999224 -255.046734 -90)
		(property "Reference" "R6461"
			(at 0 0 270)
			(layer "F.SilkS")
			(hide yes)
			(effects
				(font
					(size 1.27 1.27)
				)
			)
		)
		(property "Value" ""
			(at 0 0 270)
			(layer "F.Fab")
			(effects
				(font
					(size 1.27 1.27)
				)
			)
		)
		(duplicate_pad_numbers_are_jumpers no)
		(fp_line
			(start -0.7874 0.4064)
			(end -0.7874 -0.4064)
			(stroke
				(width 0.1524)
				(type default)
			)
			(layer "F.SilkS")
		)
		(fp_line
			(start 0.7874 0.4064)
			(end -0.7874 0.4064)
			(stroke
				(width 0.1524)
				(type default)
			)
			(layer "F.SilkS")
		)
		(fp_line
			(start -0.7874 -0.4064)
			(end 0.7874 -0.4064)
			(stroke
				(width 0.1524)
				(type default)
			)
			(layer "F.SilkS")
		)
		(fp_line
			(start 0.7874 -0.4064)
			(end 0.7874 0.4064)
			(stroke
				(width 0.1524)
				(type default)
			)
			(layer "F.SilkS")
		)
		(fp_line
			(start -0.67945 0.3048)
			(end -0.67945 -0.305054)
			(stroke
				(width 0.1)
				(type default)
			)
			(layer "F.Fab")
		)
		(fp_line
			(start -0.12065 0.3048)
			(end -0.67945 0.3048)
			(stroke
				(width 0.1)
				(type default)
			)
			(layer "F.Fab")
		)
		(fp_line
			(start 0.120396 0.3048)
			(end 0.120396 0.2794)
			(stroke
				(width 0.1)
				(type default)
			)
			(layer "F.Fab")
		)
		(fp_line
			(start 0.67945 0.3048)
			(end 0.120396 0.3048)
			(stroke
				(width 0.1)
				(type default)
			)
			(layer "F.Fab")
		)
		(fp_line
			(start -0.12065 0.2794)
			(end -0.12065 0.3048)
			(stroke
				(width 0.1)
				(type default)
			)
			(layer "F.Fab")
		)
		(fp_line
			(start 0.120396 0.2794)
			(end -0.12065 0.2794)
			(stroke
				(width 0.1)
				(type default)
			)
			(layer "F.Fab")
		)
		(fp_line
			(start -0.12065 -0.2794)
			(end 0.12065 -0.2794)
			(stroke
				(width 0.1)
				(type default)
			)
			(layer "F.Fab")
		)
		(fp_line
			(start 0.12065 -0.2794)
			(end 0.12065 -0.3048)
			(stroke
				(width 0.1)
				(type default)
			)
			(layer "F.Fab")
		)
		(fp_line
			(start 0.12065 -0.3048)
			(end 0.67945 -0.3048)
			(stroke
				(width 0.1)
				(type default)
			)
			(layer "F.Fab")
		)
		(fp_line
			(start 0.67945 -0.3048)
			(end 0.67945 0.3048)
			(stroke
				(width 0.1)
				(type default)
			)
			(layer "F.Fab")
		)
		(fp_line
			(start -0.67945 -0.305054)
			(end -0.12065 -0.305054)
			(stroke
				(width 0.1)
				(type default)
			)
			(layer "F.Fab")
		)
		(fp_line
			(start -0.12065 -0.305054)
			(end -0.12065 -0.2794)
			(stroke
				(width 0.1)
				(type default)
			)
			(layer "F.Fab")
		)
		(pad "1" smd circle
			(at -0.40005 0 270)
			(size 0 0)
			(layers "F.Cu" "F.Mask" "F.Paste")
			(net "P1V25_SERDES_VDDPLL_PEX0")
		)
		(pad "2" smd circle
			(at 0.40005 0 270)
			(size 0 0)
			(layers "F.Cu" "F.Mask" "F.Paste")
			(net "P1V25_SERDES_VDDPLL_PEX0_C0")
		)
	)
)
